(kicad_pcb
	(version 20260206)
	(generator "pcbnew")
	(generator_version "10.0")
	(general
		(thickness 1.6)
		(legacy_teardrops no)
	)
	(paper "A4")
	(title_block
		(title "12092022_DA0F0TFB6D0_F0T_FAN_BOARD_MP5048_D_brd_v02_OCP.brd")
		(comment 1 "Grand Teton / footprints 918-923 of 924")
	)
	(layers
		(0 "F.Cu" signal "TOP")
		(4 "In1.Cu" signal "GND")
		(6 "In2.Cu" signal "IN1")
		(8 "In3.Cu" signal "IN2")
		(10 "In4.Cu" signal "GND1")
		(2 "B.Cu" signal "BOTTOM")
		(9 "F.Adhes" user "F.Adhesive")
		(11 "B.Adhes" user "B.Adhesive")
		(13 "F.Paste" user "Package Geometry/Pastemask Top")
		(15 "B.Paste" user "Package Geometry/Pastemask Bottom")
		(5 "F.SilkS" user "Ref Des/Silkscreen Top")
		(7 "B.SilkS" user "Ref Des/Silkscreen Bottom")
		(1 "F.Mask" user "Board Geometry/Soldermask Top")
		(3 "B.Mask" user "Board Geometry/Soldermask Bottom")
		(17 "Dwgs.User" user "User.Drawings")
		(19 "Cmts.User" user "User.Comments")
		(21 "Eco1.User" user "User.Eco1")
		(23 "Eco2.User" user "User.Eco2")
		(25 "Edge.Cuts" user "Board Geometry/Outline")
		(27 "Margin" user)
		(31 "F.CrtYd" user "Package Geometry/Place Bound Top")
		(29 "B.CrtYd" user "Package Geometry/Place Bound Bottom")
		(35 "F.Fab" user "Ref Des/Assembly Top")
		(33 "B.Fab" user "Ref Des/Assembly Bottom")
	)
	(footprint ""
		(layer "B.Cu")
		(at 38.71468 -73.962768 90)
		(property "Reference" "PR40"
			(at 0 0 90)
			(layer "B.SilkS")
			(hide yes)
			(effects
				(font
					(size 1.27 1.27)
				)
				(justify mirror)
			)
		)
		(property "Value" ""
			(at 0 0 90)
			(layer "B.Fab")
			(effects
				(font
					(size 1.27 1.27)
				)
				(justify mirror)
			)
		)
		(duplicate_pad_numbers_are_jumpers no)
		(fp_line
			(start 0.7874 -0.4064)
			(end -0.7874 -0.4064)
			(stroke
				(width 0.1524)
				(type default)
			)
			(layer "B.SilkS")
		)
		(fp_line
			(start -0.7874 -0.4064)
			(end -0.7874 0.4064)
			(stroke
				(width 0.1524)
				(type default)
			)
			(layer "B.SilkS")
		)
		(fp_line
			(start 0.7874 0.4064)
			(end 0.7874 -0.4064)
			(stroke
				(width 0.1524)
				(type default)
			)
			(layer "B.SilkS")
		)
		(fp_line
			(start -0.7874 0.4064)
			(end 0.7874 0.4064)
			(stroke
				(width 0.1524)
				(type default)
			)
			(layer "B.SilkS")
		)
		(fp_line
			(start 0.67945 -0.305054)
			(end 0.12065 -0.305054)
			(stroke
				(width 0.1)
				(type default)
			)
			(layer "B.Fab")
		)
		(fp_line
			(start 0.12065 -0.305054)
			(end 0.12065 -0.2794)
			(stroke
				(width 0.1)
				(type default)
			)
			(layer "B.Fab")
		)
		(fp_line
			(start -0.12065 -0.3048)
			(end -0.67945 -0.3048)
			(stroke
				(width 0.1)
				(type default)
			)
			(layer "B.Fab")
		)
		(fp_line
			(start -0.67945 -0.3048)
			(end -0.67945 0.3048)
			(stroke
				(width 0.1)
				(type default)
			)
			(layer "B.Fab")
		)
		(fp_line
			(start 0.12065 -0.2794)
			(end -0.12065 -0.2794)
			(stroke
				(width 0.1)
				(type default)
			)
			(layer "B.Fab")
		)
		(fp_line
			(start -0.12065 -0.2794)
			(end -0.12065 -0.3048)
			(stroke
				(width 0.1)
				(type default)
			)
			(layer "B.Fab")
		)
		(fp_line
			(start 0.12065 0.2794)
			(end 0.12065 0.3048)
			(stroke
				(width 0.1)
				(type default)
			)
			(layer "B.Fab")
		)
		(fp_line
			(start -0.120396 0.2794)
			(end 0.12065 0.2794)
			(stroke
				(width 0.1)
				(type default)
			)
			(layer "B.Fab")
		)
		(fp_line
			(start 0.67945 0.3048)
			(end 0.67945 -0.305054)
			(stroke
				(width 0.1)
				(type default)
			)
			(layer "B.Fab")
		)
		(fp_line
			(start 0.12065 0.3048)
			(end 0.67945 0.3048)
			(stroke
				(width 0.1)
				(type default)
			)
			(layer "B.Fab")
		)
		(fp_line
			(start -0.120396 0.3048)
			(end -0.120396 0.2794)
			(stroke
				(width 0.1)
				(type default)
			)
			(layer "B.Fab")
		)
		(fp_line
			(start -0.67945 0.3048)
			(end -0.120396 0.3048)
			(stroke
				(width 0.1)
				(type default)
			)
			(layer "B.Fab")
		)
		(pad "1" smd circle
			(at 0.40005 0 270)
			(size 0 0)
			(layers "B.Cu" "B.Mask" "B.Paste")
			(net "FAN_2_TEMP")
		)
		(pad "2" smd circle
			(at -0.40005 0 270)
			(size 0 0)
			(layers "B.Cu" "B.Mask" "B.Paste")
			(net "GND")
		)
	)
	(footprint ""
		(layer "B.Cu")
		(at 10.746486 -64.837056 -90)
		(property "Reference" "PC2122"
			(at 0 0 90)
			(layer "B.SilkS")
			(hide yes)
			(effects
				(font
					(size 1.27 1.27)
				)
				(justify mirror)
			)
		)
		(property "Value" ""
			(at 0 0 90)
			(layer "B.Fab")
			(effects
				(font
					(size 1.27 1.27)
				)
				(justify mirror)
			)
		)
		(duplicate_pad_numbers_are_jumpers no)
		(fp_line
			(start -0.7874 0.4064)
			(end 0.7874 0.4064)
			(stroke
				(width 0.1524)
				(type default)
			)
			(layer "B.SilkS")
		)
		(fp_line
			(start 0.7874 0.4064)
			(end 0.7874 -0.4064)
			(stroke
				(width 0.1524)
				(type default)
			)
			(layer "B.SilkS")
		)
		(fp_line
			(start -0.7874 -0.4064)
			(end -0.7874 0.4064)
			(stroke
				(width 0.1524)
				(type default)
			)
			(layer "B.SilkS")
		)
		(fp_line
			(start 0.7874 -0.4064)
			(end -0.7874 -0.4064)
			(stroke
				(width 0.1524)
				(type default)
			)
			(layer "B.SilkS")
		)
		(fp_line
			(start -0.67945 0.3048)
			(end -0.120396 0.3048)
			(stroke
				(width 0.1)
				(type default)
			)
			(layer "B.Fab")
		)
		(fp_line
			(start -0.120396 0.3048)
			(end -0.120396 0.2794)
			(stroke
				(width 0.1)
				(type default)
			)
			(layer "B.Fab")
		)
		(fp_line
			(start 0.12065 0.3048)
			(end 0.67945 0.3048)
			(stroke
				(width 0.1)
				(type default)
			)
			(layer "B.Fab")
		)
		(fp_line
			(start 0.67945 0.3048)
			(end 0.67945 -0.305054)
			(stroke
				(width 0.1)
				(type default)
			)
			(layer "B.Fab")
		)
		(fp_line
			(start -0.120396 0.2794)
			(end 0.12065 0.2794)
			(stroke
				(width 0.1)
				(type default)
			)
			(layer "B.Fab")
		)
		(fp_line
			(start 0.12065 0.2794)
			(end 0.12065 0.3048)
			(stroke
				(width 0.1)
				(type default)
			)
			(layer "B.Fab")
		)
		(fp_line
			(start -0.12065 -0.2794)
			(end -0.12065 -0.3048)
			(stroke
				(width 0.1)
				(type default)
			)
			(layer "B.Fab")
		)
		(fp_line
			(start 0.12065 -0.2794)
			(end -0.12065 -0.2794)
			(stroke
				(width 0.1)
				(type default)
			)
			(layer "B.Fab")
		)
		(fp_line
			(start -0.67945 -0.3048)
			(end -0.67945 0.3048)
			(stroke
				(width 0.1)
				(type default)
			)
			(layer "B.Fab")
		)
		(fp_line
			(start -0.12065 -0.3048)
			(end -0.67945 -0.3048)
			(stroke
				(width 0.1)
				(type default)
			)
			(layer "B.Fab")
		)
		(fp_line
			(start 0.12065 -0.305054)
			(end 0.12065 -0.2794)
			(stroke
				(width 0.1)
				(type default)
			)
			(layer "B.Fab")
		)
		(fp_line
			(start 0.67945 -0.305054)
			(end 0.12065 -0.305054)
			(stroke
				(width 0.1)
				(type default)
			)
			(layer "B.Fab")
		)
		(pad "1" smd circle
			(at 0.40005 0 90)
			(size 0 0)
			(layers "B.Cu" "B.Mask" "B.Paste")
			(net "FAN_4_TEMP")
		)
		(pad "2" smd circle
			(at -0.40005 0 90)
			(size 0 0)
			(layers "B.Cu" "B.Mask" "B.Paste")
			(net "GND")
		)
	)
	(footprint ""
		(layer "B.Cu")
		(at 8.694166 -64.837056 -90)
		(property "Reference" "PC39"
			(at 0 0 90)
			(layer "B.SilkS")
			(hide yes)
			(effects
				(font
					(size 1.27 1.27)
				)
				(justify mirror)
			)
		)
		(property "Value" ""
			(at 0 0 90)
			(layer "B.Fab")
			(effects
				(font
					(size 1.27 1.27)
				)
				(justify mirror)
			)
		)
		(duplicate_pad_numbers_are_jumpers no)
		(fp_line
			(start -0.7874 0.4064)
			(end 0.7874 0.4064)
			(stroke
				(width 0.1524)
				(type default)
			)
			(layer "B.SilkS")
		)
		(fp_line
			(start 0.7874 0.4064)
			(end 0.7874 -0.4064)
			(stroke
				(width 0.1524)
				(type default)
			)
			(layer "B.SilkS")
		)
		(fp_line
			(start -0.7874 -0.4064)
			(end -0.7874 0.4064)
			(stroke
				(width 0.1524)
				(type default)
			)
			(layer "B.SilkS")
		)
		(fp_line
			(start 0.7874 -0.4064)
			(end -0.7874 -0.4064)
			(stroke
				(width 0.1524)
				(type default)
			)
			(layer "B.SilkS")
		)
		(fp_line
			(start -0.67945 0.3048)
			(end -0.120396 0.3048)
			(stroke
				(width 0.1)
				(type default)
			)
			(layer "B.Fab")
		)
		(fp_line
			(start -0.120396 0.3048)
			(end -0.120396 0.2794)
			(stroke
				(width 0.1)
				(type default)
			)
			(layer "B.Fab")
		)
		(fp_line
			(start 0.12065 0.3048)
			(end 0.67945 0.3048)
			(stroke
				(width 0.1)
				(type default)
			)
			(layer "B.Fab")
		)
		(fp_line
			(start 0.67945 0.3048)
			(end 0.67945 -0.305054)
			(stroke
				(width 0.1)
				(type default)
			)
			(layer "B.Fab")
		)
		(fp_line
			(start -0.120396 0.2794)
			(end 0.12065 0.2794)
			(stroke
				(width 0.1)
				(type default)
			)
			(layer "B.Fab")
		)
		(fp_line
			(start 0.12065 0.2794)
			(end 0.12065 0.3048)
			(stroke
				(width 0.1)
				(type default)
			)
			(layer "B.Fab")
		)
		(fp_line
			(start -0.12065 -0.2794)
			(end -0.12065 -0.3048)
			(stroke
				(width 0.1)
				(type default)
			)
			(layer "B.Fab")
		)
		(fp_line
			(start 0.12065 -0.2794)
			(end -0.12065 -0.2794)
			(stroke
				(width 0.1)
				(type default)
			)
			(layer "B.Fab")
		)
		(fp_line
			(start -0.67945 -0.3048)
			(end -0.67945 0.3048)
			(stroke
				(width 0.1)
				(type default)
			)
			(layer "B.Fab")
		)
		(fp_line
			(start -0.12065 -0.3048)
			(end -0.67945 -0.3048)
			(stroke
				(width 0.1)
				(type default)
			)
			(layer "B.Fab")
		)
		(fp_line
			(start 0.12065 -0.305054)
			(end 0.12065 -0.2794)
			(stroke
				(width 0.1)
				(type default)
			)
			(layer "B.Fab")
		)
		(fp_line
			(start 0.67945 -0.305054)
			(end 0.12065 -0.305054)
			(stroke
				(width 0.1)
				(type default)
			)
			(layer "B.Fab")
		)
		(pad "1" smd circle
			(at 0.40005 0 90)
			(size 0 0)
			(layers "B.Cu" "B.Mask" "B.Paste")
			(net "FAN_4_P5V")
		)
		(pad "2" smd circle
			(at -0.40005 0 90)
			(size 0 0)
			(layers "B.Cu" "B.Mask" "B.Paste")
			(net "GND")
		)
	)
	(footprint ""
		(layer "B.Cu")
		(at 43.053 -258.572 -90)
		(property "Reference" "PC3118"
			(at 0 0 90)
			(layer "B.SilkS")
			(hide yes)
			(effects
				(font
					(size 1.27 1.27)
				)
				(justify mirror)
			)
		)
		(property "Value" ""
			(at 0 0 90)
			(layer "B.Fab")
			(effects
				(font
					(size 1.27 1.27)
				)
				(justify mirror)
			)
		)
		(duplicate_pad_numbers_are_jumpers no)
		(fp_line
			(start -0.7874 0.4064)
			(end 0.7874 0.4064)
			(stroke
				(width 0.1524)
				(type default)
			)
			(layer "B.SilkS")
		)
		(fp_line
			(start 0.7874 0.4064)
			(end 0.7874 -0.4064)
			(stroke
				(width 0.1524)
				(type default)
			)
			(layer "B.SilkS")
		)
		(fp_line
			(start -0.7874 -0.4064)
			(end -0.7874 0.4064)
			(stroke
				(width 0.1524)
				(type default)
			)
			(layer "B.SilkS")
		)
		(fp_line
			(start 0.7874 -0.4064)
			(end -0.7874 -0.4064)
			(stroke
				(width 0.1524)
				(type default)
			)
			(layer "B.SilkS")
		)
		(fp_line
			(start -0.67945 0.3048)
			(end -0.120396 0.3048)
			(stroke
				(width 0.1)
				(type default)
			)
			(layer "B.Fab")
		)
		(fp_line
			(start -0.120396 0.3048)
			(end -0.120396 0.2794)
			(stroke
				(width 0.1)
				(type default)
			)
			(layer "B.Fab")
		)
		(fp_line
			(start 0.12065 0.3048)
			(end 0.67945 0.3048)
			(stroke
				(width 0.1)
				(type default)
			)
			(layer "B.Fab")
		)
		(fp_line
			(start 0.67945 0.3048)
			(end 0.67945 -0.305054)
			(stroke
				(width 0.1)
				(type default)
			)
			(layer "B.Fab")
		)
		(fp_line
			(start -0.120396 0.2794)
			(end 0.12065 0.2794)
			(stroke
				(width 0.1)
				(type default)
			)
			(layer "B.Fab")
		)
		(fp_line
			(start 0.12065 0.2794)
			(end 0.12065 0.3048)
			(stroke
				(width 0.1)
				(type default)
			)
			(layer "B.Fab")
		)
		(fp_line
			(start -0.12065 -0.2794)
			(end -0.12065 -0.3048)
			(stroke
				(width 0.1)
				(type default)
			)
			(layer "B.Fab")
		)
		(fp_line
			(start 0.12065 -0.2794)
			(end -0.12065 -0.2794)
			(stroke
				(width 0.1)
				(type default)
			)
			(layer "B.Fab")
		)
		(fp_line
			(start -0.67945 -0.3048)
			(end -0.67945 0.3048)
			(stroke
				(width 0.1)
				(type default)
			)
			(layer "B.Fab")
		)
		(fp_line
			(start -0.12065 -0.3048)
			(end -0.67945 -0.3048)
			(stroke
				(width 0.1)
				(type default)
			)
			(layer "B.Fab")
		)
		(fp_line
			(start 0.12065 -0.305054)
			(end 0.12065 -0.2794)
			(stroke
				(width 0.1)
				(type default)
			)
			(layer "B.Fab")
		)
		(fp_line
			(start 0.67945 -0.305054)
			(end 0.12065 -0.305054)
			(stroke
				(width 0.1)
				(type default)
			)
			(layer "B.Fab")
		)
		(pad "1" smd circle
			(at 0.40005 0 90)
			(size 0 0)
			(layers "B.Cu" "B.Mask" "B.Paste")
			(net "GND")
		)
		(pad "2" smd circle
			(at -0.40005 0 90)
			(size 0 0)
			(layers "B.Cu" "B.Mask" "B.Paste")
			(net "FAN_0_CLREF")
		)
	)
	(footprint ""
		(layer "B.Cu")
		(at 40.23868 -64.837056 -90)
		(property "Reference" "PC19"
			(at 0 0 90)
			(layer "B.SilkS")
			(hide yes)
			(effects
				(font
					(size 1.27 1.27)
				)
				(justify mirror)
			)
		)
		(property "Value" ""
			(at 0 0 90)
			(layer "B.Fab")
			(effects
				(font
					(size 1.27 1.27)
				)
				(justify mirror)
			)
		)
		(duplicate_pad_numbers_are_jumpers no)
		(fp_line
			(start -0.7874 0.4064)
			(end 0.7874 0.4064)
			(stroke
				(width 0.1524)
				(type default)
			)
			(layer "B.SilkS")
		)
		(fp_line
			(start 0.7874 0.4064)
			(end 0.7874 -0.4064)
			(stroke
				(width 0.1524)
				(type default)
			)
			(layer "B.SilkS")
		)
		(fp_line
			(start -0.7874 -0.4064)
			(end -0.7874 0.4064)
			(stroke
				(width 0.1524)
				(type default)
			)
			(layer "B.SilkS")
		)
		(fp_line
			(start 0.7874 -0.4064)
			(end -0.7874 -0.4064)
			(stroke
				(width 0.1524)
				(type default)
			)
			(layer "B.SilkS")
		)
		(fp_line
			(start -0.67945 0.3048)
			(end -0.120396 0.3048)
			(stroke
				(width 0.1)
				(type default)
			)
			(layer "B.Fab")
		)
		(fp_line
			(start -0.120396 0.3048)
			(end -0.120396 0.2794)
			(stroke
				(width 0.1)
				(type default)
			)
			(layer "B.Fab")
		)
		(fp_line
			(start 0.12065 0.3048)
			(end 0.67945 0.3048)
			(stroke
				(width 0.1)
				(type default)
			)
			(layer "B.Fab")
		)
		(fp_line
			(start 0.67945 0.3048)
			(end 0.67945 -0.305054)
			(stroke
				(width 0.1)
				(type default)
			)
			(layer "B.Fab")
		)
		(fp_line
			(start -0.120396 0.2794)
			(end 0.12065 0.2794)
			(stroke
				(width 0.1)
				(type default)
			)
			(layer "B.Fab")
		)
		(fp_line
			(start 0.12065 0.2794)
			(end 0.12065 0.3048)
			(stroke
				(width 0.1)
				(type default)
			)
			(layer "B.Fab")
		)
		(fp_line
			(start -0.12065 -0.2794)
			(end -0.12065 -0.3048)
			(stroke
				(width 0.1)
				(type default)
			)
			(layer "B.Fab")
		)
		(fp_line
			(start 0.12065 -0.2794)
			(end -0.12065 -0.2794)
			(stroke
				(width 0.1)
				(type default)
			)
			(layer "B.Fab")
		)
		(fp_line
			(start -0.67945 -0.3048)
			(end -0.67945 0.3048)
			(stroke
				(width 0.1)
				(type default)
			)
			(layer "B.Fab")
		)
		(fp_line
			(start -0.12065 -0.3048)
			(end -0.67945 -0.3048)
			(stroke
				(width 0.1)
				(type default)
			)
			(layer "B.Fab")
		)
		(fp_line
			(start 0.12065 -0.305054)
			(end 0.12065 -0.2794)
			(stroke
				(width 0.1)
				(type default)
			)
			(layer "B.Fab")
		)
		(fp_line
			(start 0.67945 -0.305054)
			(end 0.12065 -0.305054)
			(stroke
				(width 0.1)
				(type default)
			)
			(layer "B.Fab")
		)
		(pad "1" smd circle
			(at 0.40005 0 90)
			(size 0 0)
			(layers "B.Cu" "B.Mask" "B.Paste")
			(net "FAN_3_P5V")
		)
		(pad "2" smd circle
			(at -0.40005 0 90)
			(size 0 0)
			(layers "B.Cu" "B.Mask" "B.Paste")
			(net "GND")
		)
	)
	(footprint ""
		(layer "B.Cu")
		(at 9.906 -172.847 180)
		(property "Reference" "C1943"
			(at 0 0 0)
			(layer "B.SilkS")
			(hide yes)
			(effects
				(font
					(size 1.27 1.27)
				)
				(justify mirror)
			)
		)
		(property "Value" ""
			(at 0 0 0)
			(layer "B.Fab")
			(effects
				(font
					(size 1.27 1.27)
				)
				(justify mirror)
			)
		)
		(duplicate_pad_numbers_are_jumpers no)
		(fp_line
			(start 0.7874 0.4064)
			(end 0.7874 -0.4064)
			(stroke
				(width 0.1524)
				(type default)
			)
			(layer "B.SilkS")
		)
		(fp_line
			(start 0.7874 -0.4064)
			(end -0.7874 -0.4064)
			(stroke
				(width 0.1524)
				(type default)
			)
			(layer "B.SilkS")
		)
		(fp_line
			(start -0.7874 0.4064)
			(end 0.7874 0.4064)
			(stroke
				(width 0.1524)
				(type default)
			)
			(layer "B.SilkS")
		)
		(fp_line
			(start -0.7874 -0.4064)
			(end -0.7874 0.4064)
			(stroke
				(width 0.1524)
				(type default)
			)
			(layer "B.SilkS")
		)
		(fp_line
			(start 0.67945 0.3048)
			(end 0.67945 -0.305054)
			(stroke
				(width 0.1)
				(type default)
			)
			(layer "B.Fab")
		)
		(fp_line
			(start 0.67945 -0.305054)
			(end 0.12065 -0.305054)
			(stroke
				(width 0.1)
				(type default)
			)
			(layer "B.Fab")
		)
		(fp_line
			(start 0.12065 0.3048)
			(end 0.67945 0.3048)
			(stroke
				(width 0.1)
				(type default)
			)
			(layer "B.Fab")
		)
		(fp_line
			(start 0.12065 0.2794)
			(end 0.12065 0.3048)
			(stroke
				(width 0.1)
				(type default)
			)
			(layer "B.Fab")
		)
		(fp_line
			(start 0.12065 -0.2794)
			(end -0.12065 -0.2794)
			(stroke
				(width 0.1)
				(type default)
			)
			(layer "B.Fab")
		)
		(fp_line
			(start 0.12065 -0.305054)
			(end 0.12065 -0.2794)
			(stroke
				(width 0.1)
				(type default)
			)
			(layer "B.Fab")
		)
		(fp_line
			(start -0.120396 0.3048)
			(end -0.120396 0.2794)
			(stroke
				(width 0.1)
				(type default)
			)
			(layer "B.Fab")
		)
		(fp_line
			(start -0.120396 0.2794)
			(end 0.12065 0.2794)
			(stroke
				(width 0.1)
				(type default)
			)
			(layer "B.Fab")
		)
		(fp_line
			(start -0.12065 -0.2794)
			(end -0.12065 -0.3048)
			(stroke
				(width 0.1)
				(type default)
			)
			(layer "B.Fab")
		)
		(fp_line
			(start -0.12065 -0.3048)
			(end -0.67945 -0.3048)
			(stroke
				(width 0.1)
				(type default)
			)
			(layer "B.Fab")
		)
		(fp_line
			(start -0.67945 0.3048)
			(end -0.120396 0.3048)
			(stroke
				(width 0.1)
				(type default)
			)
			(layer "B.Fab")
		)
		(fp_line
			(start -0.67945 -0.3048)
			(end -0.67945 0.3048)
			(stroke
				(width 0.1)
				(type default)
			)
			(layer "B.Fab")
		)
		(pad "1" smd circle
			(at 0.40005 0)
			(size 0 0)
			(layers "B.Cu" "B.Mask" "B.Paste")
			(net "P3V3_AUX")
		)
		(pad "2" smd circle
			(at -0.40005 0)
			(size 0 0)
			(layers "B.Cu" "B.Mask" "B.Paste")
			(net "GND")
		)
	)
)
